# BARRELEYE_G2-BPX24-EVT-HW-EBOM-X00_20161124-add_2nd_source_X09-20161207-Final.xls — Component Qual Tracker (bom)
|  |  |  |  |  |  |  |  | Part to be included on following build: |  |  |  |  |  |
| Item No. | Part Group | Single/Sole/Multi | Item Description | ODM P/N | Customer PN | Vendor | Vendor P/N | X00 Build | X01 Build | X02 Build | Qual Build | Qualification Target Date | Qualification Complete Date |
|  | VR Controllers |  |  |  |  | Vendor #1 |  |  |  |  |  |  |  |
|  |  |  |  |  |  | Vendor #2 |  |  |  |  |  |  |  |
|  | FETS |  |  |  |  | Vendor #1 |  |  |  |  |  |  |  |
|  |  |  |  |  |  | Vendor #2 |  |  |  |  |  |  |  |
|  | INDUCTORS |  |  |  |  | Vendor #1 |  |  |  |  |  |  |  |
|  |  |  |  |  |  | Vendor #2 |  |  |  |  |  |  |  |
|  | VREG CAPS |  |  |  |  | Vendor #1 |  |  |  |  |  |  |  |
|  |  |  |  |  |  | Vendor #2 |  |  |  |  |  |  |  |
|  | CRYSTALS |  |  |  |  | Vendor #1 |  |  |  |  |  |  |  |
|  |  |  |  |  |  | Vendor #2 |  |  |  |  |  |  |  |
|  | CONNECTORS |  |  |  |  | Vendor #1 |  |  |  |  |  |  |  |
|  |  |  |  |  |  | Vendor #2 |  |  |  |  |  |  |  |
|  | IC'S |  |  |  |  | Vendor #1 |  |  |  |  |  |  |  |
|  |  |  |  |  |  | Vendor #2 |  |  |  |  |  |  |  |
|  | MISC. |  |  |  |  | Vendor #1 |  |  |  |  |  |  |  |
|  | (HEATSINKS) |  |  |  |  | Vendor #2 |  |  |  |  |  |  |  |
